# S9S_MB_2U (Grand Teton) — schematic netlist excerpt (pin names and nets, part order shuffled) for the footprints in the layout excerpt that follows; sources: Cadence DE-HDL packaged netlist, KiCad conversion of 03242023_DA0F0TMBIJ0_F0T_Motherboard_J_brd_V01_OCP.brd

PC1574  Q_CAPP  560UF 2.5V 20% OSCON  pkg THLF  page 275 : A = PVCCINFAON_CPU0 ; B = GND

U225  74LVC1G126SE7  74LVC1G126SE-7 IC  pkg SOT353_0-65_2X1-25  page 161
  OE  = OCP_V3_2_AUX_PWR_EN_R3
  A  = RST_SMB_SWITCH_N
  GND  = GND
  Y  = RST_HP_OCP_V3_2_R_N
  VCC  = P3V3_AUX

R4412  Q_RES  4.75K 1% CHIP  pkg 0402LF  page 123 : A = P3V3 ; B = H_CPU1_MEMTRIP_VT_N

(kicad_pcb
	(version 20260206)
	(generator "pcbnew")
	(generator_version "10.0")
	(general
		(thickness 1.6)
		(legacy_teardrops no)
	)
	(paper "A4")
	(title_block
		(title "03242023_DA0F0TMBIJ0_F0T_Motherboard_J_brd_V01_OCP.brd")
		(comment 1 "Grand Teton / footprints 1348-1350 of 6105")
	)
	(layers
		(0 "F.Cu" signal "TOP")
		(4 "In1.Cu" signal "GND")
		(6 "In2.Cu" signal "IN1")
		(8 "In3.Cu" signal "GND1")
		(10 "In4.Cu" signal "IN2")
		(12 "In5.Cu" signal "GND2")
		(14 "In6.Cu" signal "IN3")
		(16 "In7.Cu" signal "GND3")
		(18 "In8.Cu" signal "VCC")
		(20 "In9.Cu" signal "VCC1")
		(22 "In10.Cu" signal "GND4")
		(24 "In11.Cu" signal "IN4")
		(26 "In12.Cu" signal "GND5")
		(28 "In13.Cu" signal "IN5")
		(30 "In14.Cu" signal "GND6")
		(32 "In15.Cu" signal "IN6")
		(34 "In16.Cu" signal "GND7")
		(2 "B.Cu" signal "BOTTOM")
		(9 "F.Adhes" user "F.Adhesive")
		(11 "B.Adhes" user "B.Adhesive")
		(13 "F.Paste" user "Package Geometry/Pastemask Top")
		(15 "B.Paste" user "Package Geometry/Pastemask Bottom")
		(5 "F.SilkS" user "Ref Des/Silkscreen Top")
		(7 "B.SilkS" user "Ref Des/Silkscreen Bottom")
		(1 "F.Mask" user "Board Geometry/Soldermask Top")
		(3 "B.Mask" user "Board Geometry/Soldermask Bottom")
		(17 "Dwgs.User" user "User.Drawings")
		(19 "Cmts.User" user "User.Comments")
		(21 "Eco1.User" user "User.Eco1")
		(23 "Eco2.User" user "User.Eco2")
		(25 "Edge.Cuts" user "Board Geometry/Outline")
		(27 "Margin" user)
		(31 "F.CrtYd" user "Package Geometry/Place Bound Top")
		(29 "B.CrtYd" user "Package Geometry/Place Bound Bottom")
		(35 "F.Fab" user "Ref Des/Assembly Top")
		(33 "B.Fab" user "Ref Des/Assembly Bottom")
	)
	(footprint ""
		(layer "F.Cu")
		(at 152.96388 -109.311948 90)
		(property "Reference" "U225"
			(at -2.224532 -4.60248 0)
			(unlocked yes)
			(layer "F.SilkS")
			(effects
				(font
					(size 0.7874 0.5842)
					(thickness 0.1524)
				)
				(justify left)
			)
		)
		(property "Value" ""
			(at 0 0 90)
			(layer "F.Fab")
			(effects
				(font
					(size 1.27 1.27)
				)
			)
		)
		(duplicate_pad_numbers_are_jumpers no)
		(fp_line
			(start 1.400048 -1.100074)
			(end -1.400048 -1.100074)
			(stroke
				(width 0.1524)
				(type default)
			)
			(layer "F.SilkS")
		)
		(fp_line
			(start 1.400048 -1.100074)
			(end 1.400048 1.100074)
			(stroke
				(width 0.1524)
				(type default)
			)
			(layer "F.SilkS")
		)
		(fp_line
			(start 1.400048 1.100074)
			(end -1.400048 1.100074)
			(stroke
				(width 0.1524)
				(type default)
			)
			(layer "F.SilkS")
		)
		(fp_line
			(start -1.400048 1.100074)
			(end -1.400048 -1.100074)
			(stroke
				(width 0.1524)
				(type default)
			)
			(layer "F.SilkS")
		)
		(fp_poly
			(pts
				(xy -0.960374 -1.217168) (xy -1.468374 -2.233168) (xy -0.452374 -2.233168)
			)
			(stroke
				(width 0)
				(type default)
			)
			(fill yes)
			(layer "F.SilkS")
		)
		(fp_line
			(start 0.674878 -1.100074)
			(end 0.674878 1.100074)
			(stroke
				(width 0.1)
				(type default)
			)
			(layer "F.Fab")
		)
		(fp_line
			(start -0.674878 -1.100074)
			(end 0.674878 -1.100074)
			(stroke
				(width 0.1)
				(type default)
			)
			(layer "F.Fab")
		)
		(fp_line
			(start 0.674878 1.100074)
			(end -0.674878 1.100074)
			(stroke
				(width 0.1)
				(type default)
			)
			(layer "F.Fab")
		)
		(fp_line
			(start -0.674878 1.100074)
			(end -0.674878 -1.100074)
			(stroke
				(width 0.1)
				(type default)
			)
			(layer "F.Fab")
		)
		(fp_poly
			(pts
				(xy -1.590548 -0.649986) (xy -2.606548 -1.157986) (xy -2.606548 -0.141986)
			)
			(stroke
				(width 0)
				(type default)
			)
			(fill yes)
			(layer "F.Fab")
		)
		(pad "1" smd rect
			(at -0.94996 -0.649986)
			(size 0.4318 0.6096)
			(layers "F.Cu" "F.Mask" "F.Paste")
			(net "OCP_V3_2_AUX_PWR_EN_R3")
		)
		(pad "2" smd rect
			(at -0.94996 0)
			(size 0.4318 0.6096)
			(layers "F.Cu" "F.Mask" "F.Paste")
			(net "RST_SMB_SWITCH_N")
		)
		(pad "3" smd rect
			(at -0.94996 0.649986)
			(size 0.4318 0.6096)
			(layers "F.Cu" "F.Mask" "F.Paste")
			(net "GND")
		)
		(pad "4" smd rect
			(at 0.94996 0.649986)
			(size 0.4318 0.6096)
			(layers "F.Cu" "F.Mask" "F.Paste")
			(net "RST_HP_OCP_V3_2_R_N")
		)
		(pad "5" smd rect
			(at 0.94996 -0.649986)
			(size 0.4318 0.6096)
			(layers "F.Cu" "F.Mask" "F.Paste")
			(net "P3V3_AUX")
		)
	)
	(footprint ""
		(layer "F.Cu")
		(at 400.558 -177.206148)
		(property "Reference" "PC1574"
			(at 0 0 0)
			(layer "F.SilkS")
			(hide yes)
			(effects
				(font
					(size 1.27 1.27)
				)
			)
		)
		(property "Value" ""
			(at 0 0 0)
			(layer "F.Fab")
			(effects
				(font
					(size 1.27 1.27)
				)
			)
		)
		(duplicate_pad_numbers_are_jumpers no)
		(fp_line
			(start 2.750058 0.999998)
			(end -2.750058 0.999998)
			(stroke
				(width 0.1524)
				(type default)
			)
			(layer "F.SilkS")
		)
		(fp_circle
			(center 0 0.999998)
			(end 2.750058 0.999998)
			(stroke
				(width 0.1524)
				(type default)
			)
			(fill no)
			(layer "F.SilkS")
		)
		(fp_poly
			(pts
				(arc
					(start 2.750058 0.999998)
					(mid 0 3.750056)
					(end -2.750058 0.999998)
				)
			)
			(stroke
				(width 0)
				(type default)
			)
			(fill yes)
			(layer "F.SilkS")
		)
		(fp_circle
			(center 0 0.999998)
			(end 2.750058 0.999998)
			(stroke
				(width 0.1)
				(type default)
			)
			(fill no)
			(layer "F.Fab")
		)
		(pad "1" thru_hole rect
			(at 0 0)
			(size 1.5748 1.5748)
			(drill 1.0668)
			(layers "*.Cu" "*.Mask")
			(remove_unused_layers no)
			(net "PVCCINFAON_CPU0")
			(clearance 0)
			(padstack
				(mode front_inner_back)
				(layer "Inner"
					(shape circle)
					(size 1.5748 1.5748)
					(clearance 0)
				)
				(layer "B.Cu"
					(shape rect)
					(size 1.5748 1.5748)
					(clearance 0)
				)
			)
		)
		(pad "2" thru_hole circle
			(at 0 1.999996)
			(size 1.5748 1.5748)
			(drill 1.0668)
			(layers "*.Cu" "*.Mask")
			(remove_unused_layers no)
			(net "GND")
			(clearance 0)
		)
	)
	(footprint ""
		(layer "F.Cu")
		(at 134.54888 -100.167948 90)
		(property "Reference" "R4412"
			(at 0 0 90)
			(layer "F.SilkS")
			(hide yes)
			(effects
				(font
					(size 1.27 1.27)
				)
			)
		)
		(property "Value" ""
			(at 0 0 90)
			(layer "F.Fab")
			(effects
				(font
					(size 1.27 1.27)
				)
			)
		)
		(duplicate_pad_numbers_are_jumpers no)
		(fp_line
			(start 0.7874 -0.4064)
			(end 0.7874 0.4064)
			(stroke
				(width 0.1524)
				(type default)
			)
			(layer "F.SilkS")
		)
		(fp_line
			(start -0.7874 -0.4064)
			(end 0.7874 -0.4064)
			(stroke
				(width 0.1524)
				(type default)
			)
			(layer "F.SilkS")
		)
		(fp_line
			(start 0.7874 0.4064)
			(end -0.7874 0.4064)
			(stroke
				(width 0.1524)
				(type default)
			)
			(layer "F.SilkS")
		)
		(fp_line
			(start -0.7874 0.4064)
			(end -0.7874 -0.4064)
			(stroke
				(width 0.1524)
				(type default)
			)
			(layer "F.SilkS")
		)
		(fp_line
			(start -0.12065 -0.305054)
			(end -0.12065 -0.2794)
			(stroke
				(width 0.1)
				(type default)
			)
			(layer "F.Fab")
		)
		(fp_line
			(start -0.67945 -0.305054)
			(end -0.12065 -0.305054)
			(stroke
				(width 0.1)
				(type default)
			)
			(layer "F.Fab")
		)
		(fp_line
			(start 0.67945 -0.3048)
			(end 0.67945 0.3048)
			(stroke
				(width 0.1)
				(type default)
			)
			(layer "F.Fab")
		)
		(fp_line
			(start 0.12065 -0.3048)
			(end 0.67945 -0.3048)
			(stroke
				(width 0.1)
				(type default)
			)
			(layer "F.Fab")
		)
		(fp_line
			(start 0.12065 -0.2794)
			(end 0.12065 -0.3048)
			(stroke
				(width 0.1)
				(type default)
			)
			(layer "F.Fab")
		)
		(fp_line
			(start -0.12065 -0.2794)
			(end 0.12065 -0.2794)
			(stroke
				(width 0.1)
				(type default)
			)
			(layer "F.Fab")
		)
		(fp_line
			(start 0.120396 0.2794)
			(end -0.12065 0.2794)
			(stroke
				(width 0.1)
				(type default)
			)
			(layer "F.Fab")
		)
		(fp_line
			(start -0.12065 0.2794)
			(end -0.12065 0.3048)
			(stroke
				(width 0.1)
				(type default)
			)
			(layer "F.Fab")
		)
		(fp_line
			(start 0.67945 0.3048)
			(end 0.120396 0.3048)
			(stroke
				(width 0.1)
				(type default)
			)
			(layer "F.Fab")
		)
		(fp_line
			(start 0.120396 0.3048)
			(end 0.120396 0.2794)
			(stroke
				(width 0.1)
				(type default)
			)
			(layer "F.Fab")
		)
		(fp_line
			(start -0.12065 0.3048)
			(end -0.67945 0.3048)
			(stroke
				(width 0.1)
				(type default)
			)
			(layer "F.Fab")
		)
		(fp_line
			(start -0.67945 0.3048)
			(end -0.67945 -0.305054)
			(stroke
				(width 0.1)
				(type default)
			)
			(layer "F.Fab")
		)
		(pad "1" smd circle
			(at -0.40005 0 90)
			(size 0 0)
			(layers "F.Cu" "F.Mask" "F.Paste")
			(net "P3V3")
		)
		(pad "2" smd circle
			(at 0.40005 0 90)
			(size 0 0)
			(layers "F.Cu" "F.Mask" "F.Paste")
			(net "H_CPU1_MEMTRIP_VT_N")
		)
	)
)
